# SCM (Grand Teton) — schematic netlist excerpt (pin names and nets, part order shuffled) for the footprints in the layout excerpt that follows; sources: Cadence DE-HDL packaged netlist, KiCad conversion of 12092022_DA0F0TMDCD0_F0T_Management_Board_D_brd_V3_OCP.brd

R767  Q_RES  33.2 1% CHIP  pkg 0402LF  page 34 : A = FM_TPM_PRSNT_0_N ; B = FM_TPM_PRSNT_0_R_N

X7  TP_TDR_4P_FTS  TP_TDR_4P_DIP EMPTY  pkg TH  page 60
  S1  = TDR_DIFF_85_TOP_DN
  P1  = GND_P1
  P2  = GND_P1
  S2  = TDR_DIFF_85_TOP_DP

(kicad_pcb
	(version 20260206)
	(generator "pcbnew")
	(generator_version "10.0")
	(general
		(thickness 1.6)
		(legacy_teardrops no)
	)
	(paper "A4")
	(title_block
		(title "12092022_DA0F0TMDCD0_F0T_Management_Board_D_brd_V3_OCP.brd")
		(comment 1 "Grand Teton / footprints 1388-1389 of 1440")
	)
	(layers
		(0 "F.Cu" signal "TOP")
		(4 "In1.Cu" signal "GND")
		(6 "In2.Cu" signal "IN1")
		(8 "In3.Cu" signal "GND1")
		(10 "In4.Cu" signal "IN2")
		(12 "In5.Cu" signal "VCC")
		(14 "In6.Cu" signal "VCC1")
		(16 "In7.Cu" signal "IN3")
		(18 "In8.Cu" signal "GND2")
		(20 "In9.Cu" signal "IN4")
		(22 "In10.Cu" signal "GND3")
		(2 "B.Cu" signal "BOTTOM")
		(9 "F.Adhes" user "F.Adhesive")
		(11 "B.Adhes" user "B.Adhesive")
		(13 "F.Paste" user "Package Geometry/Pastemask Top")
		(15 "B.Paste" user "Package Geometry/Pastemask Bottom")
		(5 "F.SilkS" user "Ref Des/Silkscreen Top")
		(7 "B.SilkS" user "Ref Des/Silkscreen Bottom")
		(1 "F.Mask" user "Board Geometry/Soldermask Top")
		(3 "B.Mask" user "Board Geometry/Soldermask Bottom")
		(17 "Dwgs.User" user "User.Drawings")
		(19 "Cmts.User" user "User.Comments")
		(21 "Eco1.User" user "User.Eco1")
		(23 "Eco2.User" user "User.Eco2")
		(25 "Edge.Cuts" user "Board Geometry/Outline")
		(27 "Margin" user)
		(31 "F.CrtYd" user "Package Geometry/Place Bound Top")
		(29 "B.CrtYd" user "Package Geometry/Place Bound Bottom")
		(35 "F.Fab" user "Ref Des/Assembly Top")
		(33 "B.Fab" user "Ref Des/Assembly Bottom")
	)
	(footprint ""
		(layer "B.Cu")
		(at 30.31998 -88.97112 90)
		(property "Reference" "R767"
			(at 0 0 90)
			(layer "B.SilkS")
			(hide yes)
			(effects
				(font
					(size 1.27 1.27)
				)
				(justify mirror)
			)
		)
		(property "Value" ""
			(at 0 0 90)
			(layer "B.Fab")
			(effects
				(font
					(size 1.27 1.27)
				)
				(justify mirror)
			)
		)
		(duplicate_pad_numbers_are_jumpers no)
		(fp_line
			(start 0.7874 -0.4064)
			(end -0.7874 -0.4064)
			(stroke
				(width 0.1524)
				(type default)
			)
			(layer "B.SilkS")
		)
		(fp_line
			(start -0.7874 -0.4064)
			(end -0.7874 0.4064)
			(stroke
				(width 0.1524)
				(type default)
			)
			(layer "B.SilkS")
		)
		(fp_line
			(start 0.7874 0.4064)
			(end 0.7874 -0.4064)
			(stroke
				(width 0.1524)
				(type default)
			)
			(layer "B.SilkS")
		)
		(fp_line
			(start -0.7874 0.4064)
			(end 0.7874 0.4064)
			(stroke
				(width 0.1524)
				(type default)
			)
			(layer "B.SilkS")
		)
		(fp_line
			(start 0.67945 -0.305054)
			(end 0.12065 -0.305054)
			(stroke
				(width 0.1)
				(type default)
			)
			(layer "B.Fab")
		)
		(fp_line
			(start 0.12065 -0.305054)
			(end 0.12065 -0.2794)
			(stroke
				(width 0.1)
				(type default)
			)
			(layer "B.Fab")
		)
		(fp_line
			(start -0.12065 -0.3048)
			(end -0.67945 -0.3048)
			(stroke
				(width 0.1)
				(type default)
			)
			(layer "B.Fab")
		)
		(fp_line
			(start -0.67945 -0.3048)
			(end -0.67945 0.3048)
			(stroke
				(width 0.1)
				(type default)
			)
			(layer "B.Fab")
		)
		(fp_line
			(start 0.12065 -0.2794)
			(end -0.12065 -0.2794)
			(stroke
				(width 0.1)
				(type default)
			)
			(layer "B.Fab")
		)
		(fp_line
			(start -0.12065 -0.2794)
			(end -0.12065 -0.3048)
			(stroke
				(width 0.1)
				(type default)
			)
			(layer "B.Fab")
		)
		(fp_line
			(start 0.12065 0.2794)
			(end 0.12065 0.3048)
			(stroke
				(width 0.1)
				(type default)
			)
			(layer "B.Fab")
		)
		(fp_line
			(start -0.120396 0.2794)
			(end 0.12065 0.2794)
			(stroke
				(width 0.1)
				(type default)
			)
			(layer "B.Fab")
		)
		(fp_line
			(start 0.67945 0.3048)
			(end 0.67945 -0.305054)
			(stroke
				(width 0.1)
				(type default)
			)
			(layer "B.Fab")
		)
		(fp_line
			(start 0.12065 0.3048)
			(end 0.67945 0.3048)
			(stroke
				(width 0.1)
				(type default)
			)
			(layer "B.Fab")
		)
		(fp_line
			(start -0.120396 0.3048)
			(end -0.120396 0.2794)
			(stroke
				(width 0.1)
				(type default)
			)
			(layer "B.Fab")
		)
		(fp_line
			(start -0.67945 0.3048)
			(end -0.120396 0.3048)
			(stroke
				(width 0.1)
				(type default)
			)
			(layer "B.Fab")
		)
		(pad "1" smd circle
			(at 0.40005 0 270)
			(size 0 0)
			(layers "B.Cu" "B.Mask" "B.Paste")
			(net "FM_TPM_PRSNT_0_N")
		)
		(pad "2" smd circle
			(at -0.40005 0 270)
			(size 0 0)
			(layers "B.Cu" "B.Mask" "B.Paste")
			(net "FM_TPM_PRSNT_0_R_N")
		)
	)
	(footprint ""
		(layer "B.Cu")
		(at 114.554 -106.68 -90)
		(property "Reference" "X7"
			(at 2.19837 1.2192 0)
			(unlocked yes)
			(layer "B.SilkS")
			(effects
				(font
					(size 0.7874 0.5842)
					(thickness 0.1524)
				)
				(justify left mirror)
			)
		)
		(property "Value" ""
			(at 0 0 90)
			(layer "B.Fab")
			(effects
				(font
					(size 1.27 1.27)
				)
				(justify mirror)
			)
		)
		(property "Device Type" "TP_TDR_4P_FTS_TH-TP_TDR_4P_DIPA"
			(at -1.30175 1.27 180)
			(unlocked yes)
			(layer "B.Fab")
			(hide yes)
			(effects
				(font
					(size 0.635 0.4064)
					(thickness 0.1524)
				)
				(justify mirror)
			)
		)
		(property "User Part Number" "N_A"
			(at -1.30175 1.27 180)
			(unlocked yes)
			(layer "Cmts.User")
			(hide yes)
			(effects
				(font
					(size 0.635 0.4064)
					(thickness 0.1524)
				)
				(justify mirror)
			)
		)
		(duplicate_pad_numbers_are_jumpers no)
		(fp_line
			(start -2.54 3.81)
			(end -2.54 3.6703)
			(stroke
				(width 0.1524)
				(type default)
			)
			(layer "B.SilkS")
		)
		(fp_line
			(start 0 3.81)
			(end -2.54 3.81)
			(stroke
				(width 0.1524)
				(type default)
			)
			(layer "B.SilkS")
		)
		(fp_line
			(start 0 3.175)
			(end 0 3.81)
			(stroke
				(width 0.1524)
				(type default)
			)
			(layer "B.SilkS")
		)
		(fp_line
			(start -2.54 1.4097)
			(end -2.54 1.1303)
			(stroke
				(width 0.1524)
				(type default)
			)
			(layer "B.SilkS")
		)
		(fp_line
			(start 0 0.635)
			(end 0 1.905)
			(stroke
				(width 0.1524)
				(type default)
			)
			(layer "B.SilkS")
		)
		(fp_line
			(start -2.54 -1.1303)
			(end -2.54 -1.27)
			(stroke
				(width 0.1524)
				(type default)
			)
			(layer "B.SilkS")
		)
		(fp_line
			(start -2.54 -1.27)
			(end 0 -1.27)
			(stroke
				(width 0.1524)
				(type default)
			)
			(layer "B.SilkS")
		)
		(fp_line
			(start 0 -1.27)
			(end 0 -0.635)
			(stroke
				(width 0.1524)
				(type default)
			)
			(layer "B.SilkS")
		)
		(fp_poly
			(pts
				(xy 0.761746 0) (xy 2.285746 -0.762) (xy 2.285746 0.762)
			)
			(stroke
				(width 0)
				(type default)
			)
			(fill yes)
			(layer "B.SilkS")
		)
		(fp_line
			(start -2.54 3.81)
			(end -2.54 -1.27)
			(stroke
				(width 0.1)
				(type default)
			)
			(layer "B.Fab")
		)
		(fp_line
			(start 0 3.81)
			(end -2.54 3.81)
			(stroke
				(width 0.1)
				(type default)
			)
			(layer "B.Fab")
		)
		(fp_line
			(start -2.54 -1.27)
			(end 0 -1.27)
			(stroke
				(width 0.1)
				(type default)
			)
			(layer "B.Fab")
		)
		(fp_line
			(start 0 -1.27)
			(end 0 3.81)
			(stroke
				(width 0.1)
				(type default)
			)
			(layer "B.Fab")
		)
		(fp_poly
			(pts
				(xy 0.761746 0) (xy 2.285746 -0.762) (xy 2.285746 0.762)
			)
			(stroke
				(width 0)
				(type default)
			)
			(fill yes)
			(layer "B.Fab")
		)
		(pad "1" thru_hole circle
			(at 0 0 90)
			(size 1.0033 1.0033)
			(drill 0.249936)
			(layers "*.Cu" "*.Mask")
			(remove_unused_layers no)
			(net "TDR_DIFF_85_TOP_DN")
			(clearance 0.10795)
			(padstack
				(mode front_inner_back)
				(layer "Inner"
					(shape circle)
					(size 0.8001 0.8001)
					(clearance 0.1524)
				)
				(layer "B.Cu"
					(shape circle)
					(size 1.0033 1.0033)
					(thermal_gap 0.10795)
					(clearance 0.10795)
				)
			)
		)
		(pad "2" thru_hole circle
			(at -2.54 0 90)
			(size 1.9939 1.9939)
			(drill 0.249936)
			(layers "*.Cu" "*.Mask")
			(remove_unused_layers no)
			(net "GND_P1")
			(clearance 0.10795)
			(padstack
				(mode front_inner_back)
				(layer "Inner"
					(shape circle)
					(size 0.8001 0.8001)
					(clearance 0.1524)
				)
				(layer "B.Cu"
					(shape circle)
					(size 1.9939 1.9939)
					(thermal_gap 0.10795)
					(clearance 0.10795)
				)
			)
		)
		(pad "3" thru_hole circle
			(at -2.54 2.54 90)
			(size 1.9939 1.9939)
			(drill 0.249936)
			(layers "*.Cu" "*.Mask")
			(remove_unused_layers no)
			(net "GND_P1")
			(clearance 0.10795)
			(padstack
				(mode front_inner_back)
				(layer "Inner"
					(shape circle)
					(size 0.8001 0.8001)
					(clearance 0.1524)
				)
				(layer "B.Cu"
					(shape circle)
					(size 1.9939 1.9939)
					(thermal_gap 0.10795)
					(clearance 0.10795)
				)
			)
		)
		(pad "4" thru_hole circle
			(at 0 2.54 90)
			(size 1.0033 1.0033)
			(drill 0.249936)
			(layers "*.Cu" "*.Mask")
			(remove_unused_layers no)
			(net "TDR_DIFF_85_TOP_DP")
			(clearance 0.10795)
			(padstack
				(mode front_inner_back)
				(layer "Inner"
					(shape circle)
					(size 0.8001 0.8001)
					(clearance 0.1524)
				)
				(layer "B.Cu"
					(shape circle)
					(size 1.0033 1.0033)
					(thermal_gap 0.10795)
					(clearance 0.10795)
				)
			)
		)
	)
)
